# S9S_MB_2U (Grand Teton) — schematic netlist excerpt (pin names and nets, part order shuffled) for the footprints in the layout excerpt that follows; sources: Cadence DE-HDL packaged netlist, KiCad conversion of 03242023_DA0F0TMBIJ0_F0T_Motherboard_J_brd_V01_OCP.brd

C1247  Q_CAP  47UF 4V 20% X6S  pkg C0805  page 189 : A = P1V05_PCH_AUX ; B = GND
C164  Q_CAP_DIFFBUS  DIFF BUS_0.22UF 6.3V 20% X6S  pkg C0201  page 178 : \1\ = DMI_CPU0_PCH_RX_C_DP<3> ; \2\ = DMI_CPU0_PCH_RX_DP<3>
C511  Q_CAP  47UF 4V 20% X6S  pkg C0805  page 76 : A = PVCCD_HV_CPU0 ; B = GND
C1239  Q_CAP  0.1UF 25V 10% X7R  pkg 0402  page 153 : A = P3V3_OCP_SFF ; B = GND

(kicad_pcb
	(version 20260206)
	(generator "pcbnew")
	(generator_version "10.0")
	(general
		(thickness 1.6)
		(legacy_teardrops no)
	)
	(paper "A4")
	(title_block
		(title "03242023_DA0F0TMBIJ0_F0T_Motherboard_J_brd_V01_OCP.brd")
		(comment 1 "Grand Teton / footprints 5265-5268 of 6105")
	)
	(layers
		(0 "F.Cu" signal "TOP")
		(4 "In1.Cu" signal "GND")
		(6 "In2.Cu" signal "IN1")
		(8 "In3.Cu" signal "GND1")
		(10 "In4.Cu" signal "IN2")
		(12 "In5.Cu" signal "GND2")
		(14 "In6.Cu" signal "IN3")
		(16 "In7.Cu" signal "GND3")
		(18 "In8.Cu" signal "VCC")
		(20 "In9.Cu" signal "VCC1")
		(22 "In10.Cu" signal "GND4")
		(24 "In11.Cu" signal "IN4")
		(26 "In12.Cu" signal "GND5")
		(28 "In13.Cu" signal "IN5")
		(30 "In14.Cu" signal "GND6")
		(32 "In15.Cu" signal "IN6")
		(34 "In16.Cu" signal "GND7")
		(2 "B.Cu" signal "BOTTOM")
		(9 "F.Adhes" user "F.Adhesive")
		(11 "B.Adhes" user "B.Adhesive")
		(13 "F.Paste" user "Package Geometry/Pastemask Top")
		(15 "B.Paste" user "Package Geometry/Pastemask Bottom")
		(5 "F.SilkS" user "Ref Des/Silkscreen Top")
		(7 "B.SilkS" user "Ref Des/Silkscreen Bottom")
		(1 "F.Mask" user "Board Geometry/Soldermask Top")
		(3 "B.Mask" user "Board Geometry/Soldermask Bottom")
		(17 "Dwgs.User" user "User.Drawings")
		(19 "Cmts.User" user "User.Comments")
		(21 "Eco1.User" user "User.Eco1")
		(23 "Eco2.User" user "User.Eco2")
		(25 "Edge.Cuts" user "Board Geometry/Outline")
		(27 "Margin" user)
		(31 "F.CrtYd" user "Package Geometry/Place Bound Top")
		(29 "B.CrtYd" user "Package Geometry/Place Bound Bottom")
		(35 "F.Fab" user "Ref Des/Assembly Top")
		(33 "B.Fab" user "Ref Des/Assembly Bottom")
	)
	(footprint ""
		(layer "B.Cu")
		(at 342.251792 -64.088264 90)
		(property "Reference" "C164"
			(at 0 0 90)
			(layer "B.SilkS")
			(hide yes)
			(effects
				(font
					(size 1.27 1.27)
				)
				(justify mirror)
			)
		)
		(property "Value" ""
			(at 0 0 90)
			(layer "B.Fab")
			(effects
				(font
					(size 1.27 1.27)
				)
				(justify mirror)
			)
		)
		(duplicate_pad_numbers_are_jumpers no)
		(fp_line
			(start 0.299974 -0.150114)
			(end -0.299974 -0.150114)
			(stroke
				(width 0.1)
				(type default)
			)
			(layer "B.Fab")
		)
		(fp_line
			(start -0.299974 -0.150114)
			(end -0.299974 0.150114)
			(stroke
				(width 0.1)
				(type default)
			)
			(layer "B.Fab")
		)
		(fp_line
			(start 0.299974 0.150114)
			(end 0.299974 -0.150114)
			(stroke
				(width 0.1)
				(type default)
			)
			(layer "B.Fab")
		)
		(fp_line
			(start -0.299974 0.150114)
			(end 0.299974 0.150114)
			(stroke
				(width 0.1)
				(type default)
			)
			(layer "B.Fab")
		)
		(pad "1" smd rect
			(at 0.2667 0 270)
			(size 0.3048 0.381)
			(layers "B.Cu" "B.Mask" "B.Paste")
			(net "DMI_CPU0_PCH_RX_C_DP<3>")
		)
		(pad "2" smd rect
			(at -0.2667 0 270)
			(size 0.3048 0.381)
			(layers "B.Cu" "B.Mask" "B.Paste")
			(net "DMI_CPU0_PCH_RX_DP<3>")
		)
	)
	(footprint ""
		(layer "B.Cu")
		(at 302.150526 -49.06772 180)
		(property "Reference" "C1247"
			(at 0 0 0)
			(layer "B.SilkS")
			(hide yes)
			(effects
				(font
					(size 1.27 1.27)
				)
				(justify mirror)
			)
		)
		(property "Value" ""
			(at 0 0 0)
			(layer "B.Fab")
			(effects
				(font
					(size 1.27 1.27)
				)
				(justify mirror)
			)
		)
		(duplicate_pad_numbers_are_jumpers no)
		(fp_line
			(start 1.524 0.762)
			(end 1.524 -0.762)
			(stroke
				(width 0.1524)
				(type default)
			)
			(layer "B.SilkS")
		)
		(fp_line
			(start 1.524 -0.762)
			(end -1.524 -0.762)
			(stroke
				(width 0.1524)
				(type default)
			)
			(layer "B.SilkS")
		)
		(fp_line
			(start -1.524 0.762)
			(end 1.524 0.762)
			(stroke
				(width 0.1524)
				(type default)
			)
			(layer "B.SilkS")
		)
		(fp_line
			(start -1.524 -0.762)
			(end -1.524 0.762)
			(stroke
				(width 0.1524)
				(type default)
			)
			(layer "B.SilkS")
		)
		(fp_line
			(start 1.1049 0.724916)
			(end -1.1049 0.724916)
			(stroke
				(width 0.1)
				(type default)
			)
			(layer "B.Fab")
		)
		(fp_line
			(start 1.1049 -0.724916)
			(end 1.1049 0.724916)
			(stroke
				(width 0.1)
				(type default)
			)
			(layer "B.Fab")
		)
		(fp_line
			(start -1.1049 0.724916)
			(end -1.1049 -0.724916)
			(stroke
				(width 0.1)
				(type default)
			)
			(layer "B.Fab")
		)
		(fp_line
			(start -1.1049 -0.724916)
			(end 1.1049 -0.724916)
			(stroke
				(width 0.1)
				(type default)
			)
			(layer "B.Fab")
		)
		(pad "1" smd rect
			(at 0.889 0 180)
			(size 1.016 1.27)
			(layers "B.Cu" "B.Mask" "B.Paste")
			(net "P1V05_PCH_AUX")
		)
		(pad "2" smd rect
			(at -0.889 0 180)
			(size 1.016 1.27)
			(layers "B.Cu" "B.Mask" "B.Paste")
			(net "GND")
		)
	)
	(footprint ""
		(layer "B.Cu")
		(at 362.674662 -210.19389 180)
		(property "Reference" "C511"
			(at 0 0 0)
			(layer "B.SilkS")
			(hide yes)
			(effects
				(font
					(size 1.27 1.27)
				)
				(justify mirror)
			)
		)
		(property "Value" ""
			(at 0 0 0)
			(layer "B.Fab")
			(effects
				(font
					(size 1.27 1.27)
				)
				(justify mirror)
			)
		)
		(duplicate_pad_numbers_are_jumpers no)
		(fp_line
			(start 1.524 0.762)
			(end 1.524 -0.762)
			(stroke
				(width 0.1524)
				(type default)
			)
			(layer "B.SilkS")
		)
		(fp_line
			(start 1.524 -0.762)
			(end -1.524 -0.762)
			(stroke
				(width 0.1524)
				(type default)
			)
			(layer "B.SilkS")
		)
		(fp_line
			(start -1.524 0.762)
			(end 1.524 0.762)
			(stroke
				(width 0.1524)
				(type default)
			)
			(layer "B.SilkS")
		)
		(fp_line
			(start -1.524 -0.762)
			(end -1.524 0.762)
			(stroke
				(width 0.1524)
				(type default)
			)
			(layer "B.SilkS")
		)
		(fp_line
			(start 1.1049 0.724916)
			(end -1.1049 0.724916)
			(stroke
				(width 0.1)
				(type default)
			)
			(layer "B.Fab")
		)
		(fp_line
			(start 1.1049 -0.724916)
			(end 1.1049 0.724916)
			(stroke
				(width 0.1)
				(type default)
			)
			(layer "B.Fab")
		)
		(fp_line
			(start -1.1049 0.724916)
			(end -1.1049 -0.724916)
			(stroke
				(width 0.1)
				(type default)
			)
			(layer "B.Fab")
		)
		(fp_line
			(start -1.1049 -0.724916)
			(end 1.1049 -0.724916)
			(stroke
				(width 0.1)
				(type default)
			)
			(layer "B.Fab")
		)
		(pad "1" smd rect
			(at 0.889 0 180)
			(size 1.016 1.27)
			(layers "B.Cu" "B.Mask" "B.Paste")
			(net "PVCCD_HV_CPU0")
		)
		(pad "2" smd rect
			(at -0.889 0 180)
			(size 1.016 1.27)
			(layers "B.Cu" "B.Mask" "B.Paste")
			(net "GND")
		)
	)
	(footprint ""
		(layer "B.Cu")
		(at 435.549802 -11.088116 180)
		(property "Reference" "C1239"
			(at 0 0 0)
			(layer "B.SilkS")
			(hide yes)
			(effects
				(font
					(size 1.27 1.27)
				)
				(justify mirror)
			)
		)
		(property "Value" ""
			(at 0 0 0)
			(layer "B.Fab")
			(effects
				(font
					(size 1.27 1.27)
				)
				(justify mirror)
			)
		)
		(duplicate_pad_numbers_are_jumpers no)
		(fp_line
			(start 0.7874 0.4064)
			(end 0.7874 -0.4064)
			(stroke
				(width 0.1524)
				(type default)
			)
			(layer "B.SilkS")
		)
		(fp_line
			(start 0.7874 -0.4064)
			(end -0.7874 -0.4064)
			(stroke
				(width 0.1524)
				(type default)
			)
			(layer "B.SilkS")
		)
		(fp_line
			(start -0.7874 0.4064)
			(end 0.7874 0.4064)
			(stroke
				(width 0.1524)
				(type default)
			)
			(layer "B.SilkS")
		)
		(fp_line
			(start -0.7874 -0.4064)
			(end -0.7874 0.4064)
			(stroke
				(width 0.1524)
				(type default)
			)
			(layer "B.SilkS")
		)
		(fp_line
			(start 0.67945 0.3048)
			(end 0.67945 -0.305054)
			(stroke
				(width 0.1)
				(type default)
			)
			(layer "B.Fab")
		)
		(fp_line
			(start 0.67945 -0.305054)
			(end 0.12065 -0.305054)
			(stroke
				(width 0.1)
				(type default)
			)
			(layer "B.Fab")
		)
		(fp_line
			(start 0.12065 0.3048)
			(end 0.67945 0.3048)
			(stroke
				(width 0.1)
				(type default)
			)
			(layer "B.Fab")
		)
		(fp_line
			(start 0.12065 0.2794)
			(end 0.12065 0.3048)
			(stroke
				(width 0.1)
				(type default)
			)
			(layer "B.Fab")
		)
		(fp_line
			(start 0.12065 -0.2794)
			(end -0.12065 -0.2794)
			(stroke
				(width 0.1)
				(type default)
			)
			(layer "B.Fab")
		)
		(fp_line
			(start 0.12065 -0.305054)
			(end 0.12065 -0.2794)
			(stroke
				(width 0.1)
				(type default)
			)
			(layer "B.Fab")
		)
		(fp_line
			(start -0.120396 0.3048)
			(end -0.120396 0.2794)
			(stroke
				(width 0.1)
				(type default)
			)
			(layer "B.Fab")
		)
		(fp_line
			(start -0.120396 0.2794)
			(end 0.12065 0.2794)
			(stroke
				(width 0.1)
				(type default)
			)
			(layer "B.Fab")
		)
		(fp_line
			(start -0.12065 -0.2794)
			(end -0.12065 -0.3048)
			(stroke
				(width 0.1)
				(type default)
			)
			(layer "B.Fab")
		)
		(fp_line
			(start -0.12065 -0.3048)
			(end -0.67945 -0.3048)
			(stroke
				(width 0.1)
				(type default)
			)
			(layer "B.Fab")
		)
		(fp_line
			(start -0.67945 0.3048)
			(end -0.120396 0.3048)
			(stroke
				(width 0.1)
				(type default)
			)
			(layer "B.Fab")
		)
		(fp_line
			(start -0.67945 -0.3048)
			(end -0.67945 0.3048)
			(stroke
				(width 0.1)
				(type default)
			)
			(layer "B.Fab")
		)
		(pad "1" smd circle
			(at 0.40005 0)
			(size 0 0)
			(layers "B.Cu" "B.Mask" "B.Paste")
			(net "P3V3_OCP_SFF")
		)
		(pad "2" smd circle
			(at -0.40005 0)
			(size 0 0)
			(layers "B.Cu" "B.Mask" "B.Paste")
			(net "GND")
		)
	)
)
